(kicad_pcb
	(version 20260206)
	(generator "pcbnew")
	(generator_version "10.0")
	(general
		(thickness 1.6)
		(legacy_teardrops no)
	)
	(paper "A4")
	(title_block
		(title "Bryce Canyon_SCC_16316-1_OCP.brd")
		(comment 1 "Bryce Canyon / footprints 17-23 of 1561")
	)
	(layers
		(0 "F.Cu" signal "TOP")
		(4 "In1.Cu" signal "L2GND")
		(6 "In2.Cu" signal "L3")
		(8 "In3.Cu" signal "L4VCC")
		(10 "In4.Cu" signal "L5VCC")
		(12 "In5.Cu" signal "L6")
		(14 "In6.Cu" signal "L7GND")
		(2 "B.Cu" signal "BOTTOM")
		(9 "F.Adhes" user "F.Adhesive")
		(11 "B.Adhes" user "B.Adhesive")
		(13 "F.Paste" user "Package Geometry/Pastemask Top")
		(15 "B.Paste" user "Package Geometry/Pastemask Bottom")
		(5 "F.SilkS" user "Ref Des/Silkscreen Top")
		(7 "B.SilkS" user "Ref Des/Silkscreen Bottom")
		(1 "F.Mask" user "Board Geometry/Soldermask Top")
		(3 "B.Mask" user "Board Geometry/Soldermask Bottom")
		(17 "Dwgs.User" user "User.Drawings")
		(19 "Cmts.User" user "User.Comments")
		(21 "Eco1.User" user "User.Eco1")
		(23 "Eco2.User" user "User.Eco2")
		(25 "Edge.Cuts" user "Board Geometry/Outline")
		(27 "Margin" user)
		(31 "F.CrtYd" user "Package Geometry/Place Bound Top")
		(29 "B.CrtYd" user "Package Geometry/Place Bound Bottom")
		(35 "F.Fab" user "Ref Des/Assembly Top")
		(33 "B.Fab" user "Ref Des/Assembly Bottom")
	)
	(footprint ""
		(layer "F.Cu")
		(at 88.543638 -53.68036)
		(property "Reference" "R121"
			(at 0 0 0)
			(layer "F.SilkS")
			(hide yes)
			(effects
				(font
					(size 1.27 1.27)
				)
			)
		)
		(property "Value" "0R2J-2-GP"
			(at 0.064008 -3.993896 0)
			(unlocked yes)
			(layer "F.Fab")
			(hide yes)
			(effects
				(font
					(size 1.016 1.016)
					(thickness 0.1524)
				)
			)
		)
		(property "Device Type" "R402H16"
			(at 0.064008 -5.517896 0)
			(unlocked yes)
			(layer "F.Fab")
			(hide yes)
			(effects
				(font
					(size 1.016 1.016)
					(thickness 0.1524)
				)
			)
		)
		(duplicate_pad_numbers_are_jumpers no)
		(fp_line
			(start -0.508 -0.9398)
			(end -0.508 0.9398)
			(stroke
				(width 0.1524)
				(type default)
			)
			(layer "F.SilkS")
		)
		(fp_line
			(start 0.508 -0.9398)
			(end -0.508 -0.9398)
			(stroke
				(width 0.1524)
				(type default)
			)
			(layer "F.SilkS")
		)
		(fp_rect
			(start -0.508 0.9398)
			(end 0.508 -0.9398)
			(stroke
				(width 0)
				(type default)
			)
			(fill no)
			(layer "F.CrtYd")
		)
		(fp_rect
			(start -0.508 0.9398)
			(end 0.508 -0.9398)
			(stroke
				(width 0)
				(type default)
			)
			(fill no)
			(layer "F.Fab")
		)
		(pad "1" smd custom
			(at 0 -0.4445)
			(size 0.1397 0.1397)
			(layers "F.Cu" "F.Mask" "F.Paste")
			(net "EXP_REF_CLK_N")
			(options
				(clearance outline)
				(anchor circle)
			)
			(primitives
				(gr_poly
					(pts
						(arc
							(start -0.1778 -0.2794)
							(mid -0.249642 -0.249642)
							(end -0.2794 -0.1778)
						)
						(arc
							(start -0.2794 0.1778)
							(mid -0.249642 0.249642)
							(end -0.1778 0.2794)
						)
						(arc
							(start 0.1778 0.2794)
							(mid 0.249642 0.249642)
							(end 0.2794 0.1778)
						)
						(arc
							(start 0.2794 -0.1778)
							(mid 0.249642 -0.249642)
							(end 0.1778 -0.2794)
						)
					)
					(width 0)
					(fill yes)
				)
			)
		)
		(pad "2" smd custom
			(at 0 0.4445)
			(size 0.1397 0.1397)
			(layers "F.Cu" "F.Mask" "F.Paste")
			(net "EXP_REF_CLK_R_N")
			(options
				(clearance outline)
				(anchor circle)
			)
			(primitives
				(gr_poly
					(pts
						(arc
							(start -0.1778 -0.2794)
							(mid -0.249642 -0.249642)
							(end -0.2794 -0.1778)
						)
						(arc
							(start -0.2794 0.1778)
							(mid -0.249642 0.249642)
							(end -0.1778 0.2794)
						)
						(arc
							(start 0.1778 0.2794)
							(mid 0.249642 0.249642)
							(end 0.2794 0.1778)
						)
						(arc
							(start 0.2794 -0.1778)
							(mid 0.249642 -0.249642)
							(end 0.1778 -0.2794)
						)
					)
					(width 0)
					(fill yes)
				)
			)
		)
	)
	(footprint ""
		(layer "F.Cu")
		(at 7.366 -80.899 -90)
		(property "Reference" "R344"
			(at 0 0 270)
			(layer "F.SilkS")
			(hide yes)
			(effects
				(font
					(size 1.27 1.27)
				)
			)
		)
		(property "Value" "4K7R2F-GP"
			(at 0.064008 -3.993896 270)
			(unlocked yes)
			(layer "F.Fab")
			(hide yes)
			(effects
				(font
					(size 1.016 1.016)
					(thickness 0.1524)
				)
			)
		)
		(property "Device Type" "R402H16"
			(at 0.064008 -5.517896 270)
			(unlocked yes)
			(layer "F.Fab")
			(hide yes)
			(effects
				(font
					(size 1.016 1.016)
					(thickness 0.1524)
				)
			)
		)
		(duplicate_pad_numbers_are_jumpers no)
		(fp_line
			(start -0.508 -0.9398)
			(end -0.508 0.9398)
			(stroke
				(width 0.1524)
				(type default)
			)
			(layer "F.SilkS")
		)
		(fp_line
			(start 0.508 -0.9398)
			(end -0.508 -0.9398)
			(stroke
				(width 0.1524)
				(type default)
			)
			(layer "F.SilkS")
		)
		(fp_rect
			(start -0.508 0.9398)
			(end 0.508 -0.9398)
			(stroke
				(width 0)
				(type default)
			)
			(fill no)
			(layer "F.CrtYd")
		)
		(fp_rect
			(start -0.508 0.9398)
			(end 0.508 -0.9398)
			(stroke
				(width 0)
				(type default)
			)
			(fill no)
			(layer "F.Fab")
		)
		(pad "1" smd custom
			(at 0 -0.4445 270)
			(size 0.1397 0.1397)
			(layers "F.Cu" "F.Mask" "F.Paste")
			(net "EXP_EEPROM_A0")
			(options
				(clearance outline)
				(anchor circle)
			)
			(primitives
				(gr_poly
					(pts
						(arc
							(start -0.1778 -0.2794)
							(mid -0.249642 -0.249642)
							(end -0.2794 -0.1778)
						)
						(arc
							(start -0.2794 0.1778)
							(mid -0.249642 0.249642)
							(end -0.1778 0.2794)
						)
						(arc
							(start 0.1778 0.2794)
							(mid 0.249642 0.249642)
							(end 0.2794 0.1778)
						)
						(arc
							(start 0.2794 -0.1778)
							(mid 0.249642 -0.249642)
							(end 0.1778 -0.2794)
						)
					)
					(width 0)
					(fill yes)
				)
			)
		)
		(pad "2" smd custom
			(at 0 0.4445 270)
			(size 0.1397 0.1397)
			(layers "F.Cu" "F.Mask" "F.Paste")
			(net "GND")
			(options
				(clearance outline)
				(anchor circle)
			)
			(primitives
				(gr_poly
					(pts
						(arc
							(start -0.1778 -0.2794)
							(mid -0.249642 -0.249642)
							(end -0.2794 -0.1778)
						)
						(arc
							(start -0.2794 0.1778)
							(mid -0.249642 0.249642)
							(end -0.1778 0.2794)
						)
						(arc
							(start 0.1778 0.2794)
							(mid 0.249642 0.249642)
							(end 0.2794 0.1778)
						)
						(arc
							(start 0.2794 -0.1778)
							(mid 0.249642 -0.249642)
							(end 0.1778 -0.2794)
						)
					)
					(width 0)
					(fill yes)
				)
			)
		)
	)
	(footprint ""
		(layer "F.Cu")
		(at 175.7934 -77.8002 90)
		(property "Reference" "C384"
			(at 0 0 90)
			(layer "F.SilkS")
			(hide yes)
			(effects
				(font
					(size 1.27 1.27)
				)
			)
		)
		(property "Value" "SC22U6D3V3MX-9-GP-U"
			(at 0 -2.8194 90)
			(unlocked yes)
			(layer "F.Fab")
			(hide yes)
			(effects
				(font
					(size 1.016 1.016)
					(thickness 0.1524)
				)
			)
		)
		(property "Device Type" "C603H40"
			(at 0 -4.3434 90)
			(unlocked yes)
			(layer "F.Fab")
			(hide yes)
			(effects
				(font
					(size 1.016 1.016)
					(thickness 0.1524)
				)
			)
		)
		(duplicate_pad_numbers_are_jumpers no)
		(fp_line
			(start 0.508 0)
			(end -0.508 0)
			(stroke
				(width 0.2032)
				(type default)
			)
			(layer "F.SilkS")
		)
		(fp_rect
			(start -0.5842 1.3335)
			(end 0.5842 -1.3335)
			(stroke
				(width 0)
				(type default)
			)
			(fill no)
			(layer "F.CrtYd")
		)
		(fp_rect
			(start -0.5842 1.3335)
			(end 0.5842 -1.3335)
			(stroke
				(width 0)
				(type default)
			)
			(fill no)
			(layer "F.Fab")
		)
		(pad "1" smd custom
			(at 0 -0.762 90)
			(size 0.2159 0.2159)
			(layers "F.Cu" "F.Mask" "F.Paste")
			(net "PCE_AVDD")
			(options
				(clearance outline)
				(anchor circle)
			)
			(primitives
				(gr_poly
					(pts
						(arc
							(start -0.3302 -0.4318)
							(mid -0.402042 -0.402042)
							(end -0.4318 -0.3302)
						)
						(arc
							(start -0.4318 0.3302)
							(mid -0.402042 0.402042)
							(end -0.3302 0.4318)
						)
						(arc
							(start 0.3302 0.4318)
							(mid 0.402042 0.402042)
							(end 0.4318 0.3302)
						)
						(arc
							(start 0.4318 -0.3302)
							(mid 0.402042 -0.402042)
							(end 0.3302 -0.4318)
						)
					)
					(width 0)
					(fill yes)
				)
			)
		)
		(pad "2" smd custom
			(at 0 0.762 90)
			(size 0.2159 0.2159)
			(layers "F.Cu" "F.Mask" "F.Paste")
			(net "GND")
			(options
				(clearance outline)
				(anchor circle)
			)
			(primitives
				(gr_poly
					(pts
						(arc
							(start -0.3302 -0.4318)
							(mid -0.402042 -0.402042)
							(end -0.4318 -0.3302)
						)
						(arc
							(start -0.4318 0.3302)
							(mid -0.402042 0.402042)
							(end -0.3302 0.4318)
						)
						(arc
							(start 0.3302 0.4318)
							(mid 0.402042 0.402042)
							(end 0.4318 0.3302)
						)
						(arc
							(start 0.4318 -0.3302)
							(mid 0.402042 -0.402042)
							(end 0.3302 -0.4318)
						)
					)
					(width 0)
					(fill yes)
				)
			)
		)
	)
	(footprint ""
		(layer "F.Cu")
		(at 18.797778 -100.43033 -90)
		(property "Reference" "U119"
			(at 0 0 270)
			(layer "F.SilkS")
			(hide yes)
			(effects
				(font
					(size 1.27 1.27)
				)
			)
		)
		(property "Value" "NX3L1G66GW-GP"
			(at -2.3368 -8.6868 270)
			(unlocked yes)
			(layer "F.Fab")
			(hide yes)
			(effects
				(font
					(size 1.016 1.016)
					(thickness 0.1524)
				)
			)
		)
		(property "Device Type" "SC70-5H44"
			(at -2.3114 -10.414 270)
			(unlocked yes)
			(layer "F.Fab")
			(hide yes)
			(effects
				(font
					(size 1.016 1.016)
					(thickness 0.1524)
				)
			)
		)
		(duplicate_pad_numbers_are_jumpers no)
		(fp_line
			(start -1.27 1.7018)
			(end -1.27 -1.7018)
			(stroke
				(width 0.1524)
				(type default)
			)
			(layer "F.SilkS")
		)
		(fp_line
			(start 1.27 1.7018)
			(end -1.27 1.7018)
			(stroke
				(width 0.1524)
				(type default)
			)
			(layer "F.SilkS")
		)
		(fp_line
			(start -1.27 -1.7018)
			(end 1.27 -1.7018)
			(stroke
				(width 0.1524)
				(type default)
			)
			(layer "F.SilkS")
		)
		(fp_line
			(start 1.27 -1.7018)
			(end 1.27 1.7018)
			(stroke
				(width 0.1524)
				(type default)
			)
			(layer "F.SilkS")
		)
		(fp_line
			(start 0.6604 -1.8034)
			(end 1.3843 -1.8034)
			(stroke
				(width 0.3302)
				(type default)
			)
			(layer "F.SilkS")
		)
		(fp_line
			(start 1.3843 -1.8034)
			(end 1.3843 -1.1176)
			(stroke
				(width 0.3302)
				(type default)
			)
			(layer "F.SilkS")
		)
		(fp_rect
			(start -1.524 1.9558)
			(end 1.524 -1.9558)
			(stroke
				(width 0)
				(type default)
			)
			(fill no)
			(layer "F.CrtYd")
		)
		(fp_poly
			(pts
				(xy -1.524 -1.9558) (xy 1.524 -1.9558) (xy 1.524 1.9558) (xy -1.524 1.9558)
			)
			(stroke
				(width 0)
				(type default)
			)
			(fill no)
			(layer "F.Fab")
		)
		(pad "1" smd rect
			(at 0.65024 -0.8255 270)
			(size 0.4064 1.2192)
			(layers "F.Cu" "F.Mask" "F.Paste")
			(net "SCC_STBY_PGOOD_BUF")
		)
		(pad "2" smd rect
			(at 0 -0.8255 270)
			(size 0.4064 1.2192)
			(layers "F.Cu" "F.Mask" "F.Paste")
			(net "SCC_STBY_PGOOD_R")
		)
		(pad "3" smd rect
			(at -0.65024 -0.8255 270)
			(size 0.4064 1.2192)
			(layers "F.Cu" "F.Mask" "F.Paste")
			(net "GND")
		)
		(pad "4" smd rect
			(at -0.65024 0.8255 270)
			(size 0.4064 1.2192)
			(layers "F.Cu" "F.Mask" "F.Paste")
			(net "U119_EN")
		)
		(pad "5" smd rect
			(at 0.65024 0.8255 270)
			(size 0.4064 1.2192)
			(layers "F.Cu" "F.Mask" "F.Paste")
			(net "P3V3")
		)
	)
	(footprint ""
		(layer "F.Cu")
		(at 194.801998 -71.411846 90)
		(property "Reference" "U22"
			(at 0 0 90)
			(layer "F.SilkS")
			(hide yes)
			(effects
				(font
					(size 1.27 1.27)
				)
			)
		)
		(property "Value" "TXS0102DCUR-1-GP"
			(at 0 -11.1252 90)
			(unlocked yes)
			(layer "F.Fab")
			(hide yes)
			(effects
				(font
					(size 1.016 1.016)
					(thickness 0.1524)
				)
			)
		)
		(property "Device Type" "SSOIC8-4H36"
			(at 0 -12.6492 90)
			(unlocked yes)
			(layer "F.Fab")
			(hide yes)
			(effects
				(font
					(size 1.016 1.016)
					(thickness 0.1524)
				)
			)
		)
		(duplicate_pad_numbers_are_jumpers no)
		(fp_line
			(start 1.2573 -2.1844)
			(end 1.2573 2.1844)
			(stroke
				(width 0.1524)
				(type default)
			)
			(layer "F.SilkS")
		)
		(fp_line
			(start -1.2573 -2.1844)
			(end 1.2573 -2.1844)
			(stroke
				(width 0.1524)
				(type default)
			)
			(layer "F.SilkS")
		)
		(fp_line
			(start -1.2192 -0.3556)
			(end -0.9017 -0.0381)
			(stroke
				(width 0.1524)
				(type default)
			)
			(layer "F.SilkS")
		)
		(fp_line
			(start -1.2573 -0.3556)
			(end -1.2192 -0.3556)
			(stroke
				(width 0.1524)
				(type default)
			)
			(layer "F.SilkS")
		)
		(fp_line
			(start -0.9017 -0.0381)
			(end -1.2065 0.2667)
			(stroke
				(width 0.1524)
				(type default)
			)
			(layer "F.SilkS")
		)
		(fp_line
			(start -1.2065 0.2667)
			(end -1.27 0.2667)
			(stroke
				(width 0.1524)
				(type default)
			)
			(layer "F.SilkS")
		)
		(fp_line
			(start -1.2954 0.4572)
			(end -1.2954 2.159)
			(stroke
				(width 0.4064)
				(type default)
			)
			(layer "F.SilkS")
		)
		(fp_line
			(start 1.2573 2.1844)
			(end -1.2573 2.1844)
			(stroke
				(width 0.1524)
				(type default)
			)
			(layer "F.SilkS")
		)
		(fp_line
			(start -1.2573 2.1844)
			(end -1.2573 -2.1844)
			(stroke
				(width 0.1524)
				(type default)
			)
			(layer "F.SilkS")
		)
		(fp_poly
			(pts
				(xy -1.5113 2.4384) (xy 1.5113 2.4384) (xy 1.5113 -2.4384) (xy -1.5113 -2.4384)
			)
			(stroke
				(width 0)
				(type default)
			)
			(fill no)
			(layer "F.CrtYd")
		)
		(fp_poly
			(pts
				(xy -1.5113 -2.4384) (xy 1.5113 -2.4384) (xy 1.5113 2.4384) (xy -1.5113 2.4384)
			)
			(stroke
				(width 0)
				(type default)
			)
			(fill no)
			(layer "F.Fab")
		)
		(pad "1" smd rect
			(at -0.75057 1.1684 90)
			(size 0.3048 1.524)
			(layers "F.Cu" "F.Mask" "F.Paste")
			(net "IOC_UART_R_RX")
		)
		(pad "2" smd rect
			(at -0.25019 1.1684 90)
			(size 0.3048 1.524)
			(layers "F.Cu" "F.Mask" "F.Paste")
			(net "GND")
		)
		(pad "3" smd rect
			(at 0.25019 1.1684 90)
			(size 0.3048 1.524)
			(layers "F.Cu" "F.Mask" "F.Paste")
			(net "P1V8_C")
		)
		(pad "4" smd rect
			(at 0.75057 1.1684 90)
			(size 0.3048 1.524)
			(layers "F.Cu" "F.Mask" "F.Paste")
			(net "IOC_UART_0_RX_R")
		)
		(pad "5" smd rect
			(at 0.75057 -1.1684 90)
			(size 0.3048 1.524)
			(layers "F.Cu" "F.Mask" "F.Paste")
			(net "IOC_UART_0_TX_R")
		)
		(pad "6" smd rect
			(at 0.25019 -1.1684 90)
			(size 0.3048 1.524)
			(layers "F.Cu" "F.Mask" "F.Paste")
			(net "PCIE_RST_N")
		)
		(pad "7" smd rect
			(at -0.25019 -1.1684 90)
			(size 0.3048 1.524)
			(layers "F.Cu" "F.Mask" "F.Paste")
			(net "P3V3")
		)
		(pad "8" smd rect
			(at -0.75057 -1.1684 90)
			(size 0.3048 1.524)
			(layers "F.Cu" "F.Mask" "F.Paste")
			(net "IOC_UART_R_TX")
		)
	)
	(footprint ""
		(layer "F.Cu")
		(at 7.7978 -70.4088)
		(property "Reference" "R362"
			(at 0 0 0)
			(layer "F.SilkS")
			(hide yes)
			(effects
				(font
					(size 1.27 1.27)
				)
			)
		)
		(property "Value" "4K7R2F-GP"
			(at 0.064008 -3.993896 0)
			(unlocked yes)
			(layer "F.Fab")
			(hide yes)
			(effects
				(font
					(size 1.016 1.016)
					(thickness 0.1524)
				)
			)
		)
		(property "Device Type" "R402H16"
			(at 0.064008 -5.517896 0)
			(unlocked yes)
			(layer "F.Fab")
			(hide yes)
			(effects
				(font
					(size 1.016 1.016)
					(thickness 0.1524)
				)
			)
		)
		(duplicate_pad_numbers_are_jumpers no)
		(fp_line
			(start -0.508 -0.9398)
			(end -0.508 0.9398)
			(stroke
				(width 0.1524)
				(type default)
			)
			(layer "F.SilkS")
		)
		(fp_line
			(start 0.508 -0.9398)
			(end -0.508 -0.9398)
			(stroke
				(width 0.1524)
				(type default)
			)
			(layer "F.SilkS")
		)
		(fp_rect
			(start -0.508 0.9398)
			(end 0.508 -0.9398)
			(stroke
				(width 0)
				(type default)
			)
			(fill no)
			(layer "F.CrtYd")
		)
		(fp_rect
			(start -0.508 0.9398)
			(end 0.508 -0.9398)
			(stroke
				(width 0)
				(type default)
			)
			(fill no)
			(layer "F.Fab")
		)
		(pad "1" smd custom
			(at 0 -0.4445)
			(size 0.1397 0.1397)
			(layers "F.Cu" "F.Mask" "F.Paste")
			(net "FRU_EEPROM_A2")
			(options
				(clearance outline)
				(anchor circle)
			)
			(primitives
				(gr_poly
					(pts
						(arc
							(start -0.1778 -0.2794)
							(mid -0.249642 -0.249642)
							(end -0.2794 -0.1778)
						)
						(arc
							(start -0.2794 0.1778)
							(mid -0.249642 0.249642)
							(end -0.1778 0.2794)
						)
						(arc
							(start 0.1778 0.2794)
							(mid 0.249642 0.249642)
							(end 0.2794 0.1778)
						)
						(arc
							(start 0.2794 -0.1778)
							(mid 0.249642 -0.249642)
							(end 0.1778 -0.2794)
						)
					)
					(width 0)
					(fill yes)
				)
			)
		)
		(pad "2" smd custom
			(at 0 0.4445)
			(size 0.1397 0.1397)
			(layers "F.Cu" "F.Mask" "F.Paste")
			(net "GND")
			(options
				(clearance outline)
				(anchor circle)
			)
			(primitives
				(gr_poly
					(pts
						(arc
							(start -0.1778 -0.2794)
							(mid -0.249642 -0.249642)
							(end -0.2794 -0.1778)
						)
						(arc
							(start -0.2794 0.1778)
							(mid -0.249642 0.249642)
							(end -0.1778 0.2794)
						)
						(arc
							(start 0.1778 0.2794)
							(mid 0.249642 0.249642)
							(end 0.2794 0.1778)
						)
						(arc
							(start 0.2794 -0.1778)
							(mid 0.249642 -0.249642)
							(end 0.1778 -0.2794)
						)
					)
					(width 0)
					(fill yes)
				)
			)
		)
	)
	(footprint ""
		(layer "F.Cu")
		(at 174.4726 -57.785)
		(property "Reference" "TP139"
			(at 0 0 0)
			(layer "F.SilkS")
			(hide yes)
			(effects
				(font
					(size 1.27 1.27)
				)
			)
		)
		(property "Value" "TPAD28-2-GP"
			(at -0.0127 -1.6637 0)
			(unlocked yes)
			(layer "F.Fab")
			(hide yes)
			(effects
				(font
					(size 1.016 1.016)
					(thickness 0.1524)
				)
			)
		)
		(property "Device Type" "TPAD28"
			(at -0.0127 -3.1877 0)
			(unlocked yes)
			(layer "F.Fab")
			(hide yes)
			(effects
				(font
					(size 1.016 1.016)
					(thickness 0.1524)
				)
			)
		)
		(duplicate_pad_numbers_are_jumpers no)
		(fp_poly
			(pts
				(arc
					(start 0.3556 0)
					(mid -0.3556 0)
					(end 0.3556 0)
				)
			)
			(stroke
				(width 0)
				(type default)
			)
			(fill no)
			(layer "F.CrtYd")
		)
		(fp_poly
			(pts
				(arc
					(start 0.6096 0)
					(mid -0.6096 0)
					(end 0.6096 0)
				)
			)
			(stroke
				(width 0)
				(type default)
			)
			(fill no)
			(layer "F.Fab")
		)
		(pad "1" smd circle
			(at 0 0)
			(size 0.7112 0.7112)
			(layers "F.Cu" "F.Mask" "F.Paste")
			(net "LSI_JTAG_EN_N")
		)
	)
)
